# BASEBOARD_FAB2 (Tioga Pass) — schematic netlist excerpt (pin names and nets, part order shuffled) for the footprints in the layout excerpt that follows; sources: Cadence DE-HDL packaged netlist, KiCad conversion of Wiwynn_Tioga_Pass_MB.brd

C9R10  CAP  10UF 16V 10% X6S  pkg 0805  page 207 : A = VR_FET_SW_P12V_STBY_PVCCIN_CPU1 ; B = GND
R3T10  RES  33.2 1% CHIP  pkg 0402  page 153 : A = SPI_SWITCH_MOSI ; B = SPI_SWITCH_MOSI_R1
R1U15  RES  1.00K 1% CHIP  pkg 0402  page 164 : A = FM_BOARD_SKU_ID3 ; B = GND

(kicad_pcb
	(version 20260206)
	(generator "pcbnew")
	(generator_version "10.0")
	(general
		(thickness 1.6)
		(legacy_teardrops no)
	)
	(paper "A4")
	(title_block
		(title "Wiwynn_Tioga_Pass_MB.brd")
		(comment 1 "Tioga Pass / footprints 3872-3874 of 4770")
	)
	(layers
		(0 "F.Cu" signal "TOP")
		(4 "In1.Cu" signal "L2GND")
		(6 "In2.Cu" signal "L3")
		(8 "In3.Cu" signal "L4GND")
		(10 "In4.Cu" signal "L5")
		(12 "In5.Cu" signal "L6GND")
		(14 "In6.Cu" signal "L7VCC")
		(16 "In7.Cu" signal "L8VCC")
		(18 "In8.Cu" signal "L9GND")
		(20 "In9.Cu" signal "L10")
		(22 "In10.Cu" signal "L11GND")
		(24 "In11.Cu" signal "L12")
		(26 "In12.Cu" signal "L13GND")
		(2 "B.Cu" signal "BOTTOM")
		(9 "F.Adhes" user "F.Adhesive")
		(11 "B.Adhes" user "B.Adhesive")
		(13 "F.Paste" user "Package Geometry/Pastemask Top")
		(15 "B.Paste" user "Package Geometry/Pastemask Bottom")
		(5 "F.SilkS" user "Ref Des/Silkscreen Top")
		(7 "B.SilkS" user "Ref Des/Silkscreen Bottom")
		(1 "F.Mask" user "Board Geometry/Soldermask Top")
		(3 "B.Mask" user "Board Geometry/Soldermask Bottom")
		(17 "Dwgs.User" user "User.Drawings")
		(19 "Cmts.User" user "User.Comments")
		(21 "Eco1.User" user "User.Eco1")
		(23 "Eco2.User" user "User.Eco2")
		(25 "Edge.Cuts" user "Board Geometry/Outline")
		(27 "Margin" user)
		(31 "F.CrtYd" user "Package Geometry/Place Bound Top")
		(29 "B.CrtYd" user "Package Geometry/Place Bound Bottom")
		(35 "F.Fab" user "Ref Des/Assembly Top")
		(33 "B.Fab" user "Ref Des/Assembly Bottom")
	)
	(footprint ""
		(layer "B.Cu")
		(at 387.457188 -58.57875 90)
		(property "Reference" "R3T10"
			(at 0 0 90)
			(layer "B.SilkS")
			(hide yes)
			(effects
				(font
					(size 1.27 1.27)
				)
				(justify mirror)
			)
		)
		(property "Value" ""
			(at 0 0 90)
			(layer "B.Fab")
			(effects
				(font
					(size 1.27 1.27)
				)
				(justify mirror)
			)
		)
		(duplicate_pad_numbers_are_jumpers no)
		(fp_poly
			(pts
				(xy 0.2794 -0.1016) (xy -0.2794 -0.1016) (xy -0.2794 0.9906) (xy 0.2794 0.9906)
			)
			(stroke
				(width 0)
				(type default)
			)
			(fill no)
			(layer "B.CrtYd")
		)
		(fp_line
			(start 0.2794 -0.1016)
			(end 0.2794 0.9906)
			(stroke
				(width 0.1)
				(type default)
			)
			(layer "B.Fab")
		)
		(fp_line
			(start -0.2794 -0.1016)
			(end 0.2794 -0.1016)
			(stroke
				(width 0.1)
				(type default)
			)
			(layer "B.Fab")
		)
		(fp_line
			(start 0.2794 0.9906)
			(end -0.2794 0.9906)
			(stroke
				(width 0.1)
				(type default)
			)
			(layer "B.Fab")
		)
		(fp_line
			(start -0.2794 0.9906)
			(end -0.2794 -0.1016)
			(stroke
				(width 0.1)
				(type default)
			)
			(layer "B.Fab")
		)
		(pad "1" smd rect
			(at 0 0 270)
			(size 0.508 0.508)
			(layers "B.Cu" "B.Mask" "B.Paste")
			(net "SPI_SWITCH_MOSI")
		)
		(pad "2" smd rect
			(at 0 0.889 270)
			(size 0.508 0.508)
			(layers "B.Cu" "B.Mask" "B.Paste")
			(net "SPI_SWITCH_MOSI_R1")
		)
		(zone
			(layer "B.Cu")
			(hatch none 0.5)
			(connect_pads
				(clearance 0)
			)
			(min_thickness 0.25)
			(keepout
				(tracks allowed)
				(vias not_allowed)
				(pads allowed)
				(copperpour not_allowed)
				(footprints allowed)
			)
			(placement
				(enabled no)
				(sheetname "")
			)
			(fill
				(thermal_gap 0.5)
				(thermal_bridge_width 0.5)
				(island_removal_mode 0)
			)
			(polygon
				(pts
					(xy 387.711188 -58.83275) (xy 387.711188 -58.32475) (xy 388.092188 -58.32475) (xy 388.092188 -58.83275)
				)
			)
		)
		(zone
			(layer "B.Cu")
			(hatch none 0.5)
			(connect_pads
				(clearance 0)
			)
			(min_thickness 0.25)
			(keepout
				(tracks not_allowed)
				(vias allowed)
				(pads allowed)
				(copperpour not_allowed)
				(footprints allowed)
			)
			(placement
				(enabled no)
				(sheetname "")
			)
			(fill
				(thermal_gap 0.5)
				(thermal_bridge_width 0.5)
				(island_removal_mode 0)
			)
			(polygon
				(pts
					(xy 388.092188 -58.83275) (xy 388.092188 -58.32475) (xy 387.711188 -58.32475) (xy 387.711188 -58.83275)
				)
			)
		)
	)
	(footprint ""
		(layer "B.Cu")
		(at 460.0956 -34.9504 90)
		(property "Reference" "R1U15"
			(at 0 0 90)
			(layer "B.SilkS")
			(hide yes)
			(effects
				(font
					(size 1.27 1.27)
				)
				(justify mirror)
			)
		)
		(property "Value" ""
			(at 0 0 90)
			(layer "B.Fab")
			(effects
				(font
					(size 1.27 1.27)
				)
				(justify mirror)
			)
		)
		(duplicate_pad_numbers_are_jumpers no)
		(fp_poly
			(pts
				(xy 0.2794 -0.1016) (xy -0.2794 -0.1016) (xy -0.2794 0.9906) (xy 0.2794 0.9906)
			)
			(stroke
				(width 0)
				(type default)
			)
			(fill no)
			(layer "B.CrtYd")
		)
		(fp_line
			(start 0.2794 -0.1016)
			(end 0.2794 0.9906)
			(stroke
				(width 0.1)
				(type default)
			)
			(layer "B.Fab")
		)
		(fp_line
			(start -0.2794 -0.1016)
			(end 0.2794 -0.1016)
			(stroke
				(width 0.1)
				(type default)
			)
			(layer "B.Fab")
		)
		(fp_line
			(start 0.2794 0.9906)
			(end -0.2794 0.9906)
			(stroke
				(width 0.1)
				(type default)
			)
			(layer "B.Fab")
		)
		(fp_line
			(start -0.2794 0.9906)
			(end -0.2794 -0.1016)
			(stroke
				(width 0.1)
				(type default)
			)
			(layer "B.Fab")
		)
		(pad "1" smd rect
			(at 0 0 270)
			(size 0.508 0.508)
			(layers "B.Cu" "B.Mask" "B.Paste")
			(net "FM_BOARD_SKU_ID3")
		)
		(pad "2" smd rect
			(at 0 0.889 270)
			(size 0.508 0.508)
			(layers "B.Cu" "B.Mask" "B.Paste")
			(net "GND")
		)
		(zone
			(layer "B.Cu")
			(hatch none 0.5)
			(connect_pads
				(clearance 0)
			)
			(min_thickness 0.25)
			(keepout
				(tracks allowed)
				(vias not_allowed)
				(pads allowed)
				(copperpour not_allowed)
				(footprints allowed)
			)
			(placement
				(enabled no)
				(sheetname "")
			)
			(fill
				(thermal_gap 0.5)
				(thermal_bridge_width 0.5)
				(island_removal_mode 0)
			)
			(polygon
				(pts
					(xy 460.3496 -35.2044) (xy 460.3496 -34.6964) (xy 460.7306 -34.6964) (xy 460.7306 -35.2044)
				)
			)
		)
		(zone
			(layer "B.Cu")
			(hatch none 0.5)
			(connect_pads
				(clearance 0)
			)
			(min_thickness 0.25)
			(keepout
				(tracks not_allowed)
				(vias allowed)
				(pads allowed)
				(copperpour not_allowed)
				(footprints allowed)
			)
			(placement
				(enabled no)
				(sheetname "")
			)
			(fill
				(thermal_gap 0.5)
				(thermal_bridge_width 0.5)
				(island_removal_mode 0)
			)
			(polygon
				(pts
					(xy 460.7306 -35.2044) (xy 460.7306 -34.6964) (xy 460.3496 -34.6964) (xy 460.3496 -35.2044)
				)
			)
		)
	)
	(footprint ""
		(layer "B.Cu")
		(at 32.832802 -58.297064 90)
		(property "Reference" "C9R10"
			(at 0 0 90)
			(layer "B.SilkS")
			(hide yes)
			(effects
				(font
					(size 1.27 1.27)
				)
				(justify mirror)
			)
		)
		(property "Value" ""
			(at 0 0 90)
			(layer "B.Fab")
			(effects
				(font
					(size 1.27 1.27)
				)
				(justify mirror)
			)
		)
		(duplicate_pad_numbers_are_jumpers no)
		(fp_poly
			(pts
				(xy 0.7239 -0.2159) (xy -0.7239 -0.2159) (xy -0.7239 1.9939) (xy 0.7239 1.9939)
			)
			(stroke
				(width 0)
				(type default)
			)
			(fill no)
			(layer "B.CrtYd")
		)
		(fp_line
			(start 0.7239 -0.2159)
			(end 0.7239 1.9939)
			(stroke
				(width 0.1)
				(type default)
			)
			(layer "B.Fab")
		)
		(fp_line
			(start -0.7239 -0.2159)
			(end 0.7239 -0.2159)
			(stroke
				(width 0.1)
				(type default)
			)
			(layer "B.Fab")
		)
		(fp_line
			(start 0.7239 1.9939)
			(end -0.7239 1.9939)
			(stroke
				(width 0.1)
				(type default)
			)
			(layer "B.Fab")
		)
		(fp_line
			(start -0.7239 1.9939)
			(end -0.7239 -0.2159)
			(stroke
				(width 0.1)
				(type default)
			)
			(layer "B.Fab")
		)
		(pad "1" smd rect
			(at 0 0 270)
			(size 1.27 1.016)
			(layers "B.Cu" "B.Mask" "B.Paste")
			(net "VR_FET_SW_P12V_STBY_PVCCIN_CPU1")
		)
		(pad "2" smd rect
			(at 0 1.778 270)
			(size 1.27 1.016)
			(layers "B.Cu" "B.Mask" "B.Paste")
			(net "GND")
		)
		(zone
			(layer "B.Cu")
			(hatch none 0.5)
			(connect_pads
				(clearance 0)
			)
			(min_thickness 0.25)
			(keepout
				(tracks not_allowed)
				(vias allowed)
				(pads allowed)
				(copperpour not_allowed)
				(footprints allowed)
			)
			(placement
				(enabled no)
				(sheetname "")
			)
			(fill
				(thermal_gap 0.5)
				(thermal_bridge_width 0.5)
				(island_removal_mode 0)
			)
			(polygon
				(pts
					(xy 33.340802 -58.932064) (xy 33.340802 -57.662064) (xy 34.102802 -57.662064) (xy 34.102802 -58.932064)
				)
			)
		)
	)
)
